(kicad_pcb
	(version 20260206)
	(generator "pcbnew")
	(generator_version "10.0")
	(general
		(thickness 1.6)
		(legacy_teardrops no)
	)
	(paper "A4")
	(title_block
		(title "Bryce Canyon_SCC_16316-1_OCP.brd")
		(comment 1 "Bryce Canyon / footprint 482 of 1561 (U2), pads 122-238 of 896")
	)
	(layers
		(0 "F.Cu" signal "TOP")
		(4 "In1.Cu" signal "L2GND")
		(6 "In2.Cu" signal "L3")
		(8 "In3.Cu" signal "L4VCC")
		(10 "In4.Cu" signal "L5VCC")
		(12 "In5.Cu" signal "L6")
		(14 "In6.Cu" signal "L7GND")
		(2 "B.Cu" signal "BOTTOM")
		(9 "F.Adhes" user "F.Adhesive")
		(11 "B.Adhes" user "B.Adhesive")
		(13 "F.Paste" user "Package Geometry/Pastemask Top")
		(15 "B.Paste" user "Package Geometry/Pastemask Bottom")
		(5 "F.SilkS" user "Ref Des/Silkscreen Top")
		(7 "B.SilkS" user "Ref Des/Silkscreen Bottom")
		(1 "F.Mask" user "Board Geometry/Soldermask Top")
		(3 "B.Mask" user "Board Geometry/Soldermask Bottom")
		(17 "Dwgs.User" user "User.Drawings")
		(19 "Cmts.User" user "User.Comments")
		(21 "Eco1.User" user "User.Eco1")
		(23 "Eco2.User" user "User.Eco2")
		(25 "Edge.Cuts" user "Board Geometry/Outline")
		(27 "Margin" user)
		(31 "F.CrtYd" user "Package Geometry/Place Bound Top")
		(29 "B.CrtYd" user "Package Geometry/Place Bound Bottom")
		(35 "F.Fab" user "Ref Des/Assembly Top")
		(33 "B.Fab" user "Ref Des/Assembly Bottom")
	)
	(footprint ""
		(layer "F.Cu")
		(at 174.999904 -39.99992)
		(property "Reference" "U2"
			(at 0 0 0)
			(layer "F.SilkS")
			(hide yes)
			(effects
				(font
					(size 1.27 1.27)
				)
			)
		)
		(property "Value" "SAS3008C0-1-DB-500020657-1-GP"
			(at -20.374102 -5.0292 0)
			(unlocked yes)
			(layer "F.Fab")
			(hide yes)
			(effects
				(font
					(size 1.016 1.016)
					(thickness 0.1524)
				)
			)
		)
		(property "Device Type" "BGA896D25H78"
			(at -20.374102 -6.5532 0)
			(unlocked yes)
			(layer "F.Fab")
			(hide yes)
			(effects
				(font
					(size 1.016 1.016)
					(thickness 0.1524)
				)
			)
		)
		(duplicate_pad_numbers_are_jumpers no)
		(pad "AD4" smd circle
			(at -9.19988 6.800088)
			(size 0.3556 0.3556)
			(layers "F.Cu" "F.Mask" "F.Paste")
			(net "PHY_SCC_TO_IOC_C_43_DP")
		)
		(pad "AD5" smd circle
			(at -8.400034 6.800088)
			(size 0.3556 0.3556)
			(layers "F.Cu" "F.Mask" "F.Paste")
			(net "PHY_SCC_TO_IOC_C_43_DN")
		)
		(pad "AD6" smd circle
			(at -7.599934 6.800088)
			(size 0.3556 0.3556)
			(layers "F.Cu" "F.Mask" "F.Paste")
			(net "GND")
		)
		(pad "AD7" smd circle
			(at -6.800088 6.800088)
			(size 0.3556 0.3556)
			(layers "F.Cu" "F.Mask" "F.Paste")
			(net "SAS0_AVDD")
		)
		(pad "AD8" smd circle
			(at -5.999988 6.800088)
			(size 0.3556 0.3556)
			(layers "F.Cu" "F.Mask" "F.Paste")
			(net "GND")
		)
		(pad "AD9" smd circle
			(at -5.199888 6.800088)
			(size 0.3556 0.3556)
			(layers "F.Cu" "F.Mask" "F.Paste")
			(net "PCE_AVDD")
		)
		(pad "AD10" smd circle
			(at -4.400042 6.800088)
			(size 0.3556 0.3556)
			(layers "F.Cu" "F.Mask" "F.Paste")
			(net "GND")
		)
		(pad "AD11" smd circle
			(at -3.599942 6.800088)
			(size 0.3556 0.3556)
			(layers "F.Cu" "F.Mask" "F.Paste")
			(net "PCE_AVDD")
		)
		(pad "AD12" smd circle
			(at -2.800096 6.800088)
			(size 0.3556 0.3556)
			(layers "F.Cu" "F.Mask" "F.Paste")
			(net "GND")
		)
		(pad "AD13" smd circle
			(at -1.999996 6.800088)
			(size 0.3556 0.3556)
			(layers "F.Cu" "F.Mask" "F.Paste")
			(net "PCE_AVDD")
		)
		(pad "AD14" smd circle
			(at -1.199896 6.800088)
			(size 0.3556 0.3556)
			(layers "F.Cu" "F.Mask" "F.Paste")
			(net "GND")
		)
		(pad "AD15" smd circle
			(at -0.40005 6.800088)
			(size 0.3556 0.3556)
			(layers "F.Cu" "F.Mask" "F.Paste")
			(net "PCE_AVDD")
		)
		(pad "AD16" smd circle
			(at 0.40005 6.800088)
			(size 0.3556 0.3556)
			(layers "F.Cu" "F.Mask" "F.Paste")
			(net "GND")
		)
		(pad "AD17" smd circle
			(at 1.199896 6.800088)
			(size 0.3556 0.3556)
			(layers "F.Cu" "F.Mask" "F.Paste")
			(net "GND")
		)
		(pad "AD18" smd circle
			(at 1.999996 6.800088)
			(size 0.3556 0.3556)
			(layers "F.Cu" "F.Mask" "F.Paste")
			(net "GND")
		)
		(pad "AD19" smd circle
			(at 2.800096 6.800088)
			(size 0.3556 0.3556)
			(layers "F.Cu" "F.Mask" "F.Paste")
			(net "GND")
		)
		(pad "AD20" smd circle
			(at 3.599942 6.800088)
			(size 0.3556 0.3556)
			(layers "F.Cu" "F.Mask" "F.Paste")
			(net "GND")
		)
		(pad "AD21" smd circle
			(at 4.400042 6.800088)
			(size 0.3556 0.3556)
			(layers "F.Cu" "F.Mask" "F.Paste")
			(net "GND")
		)
		(pad "AD22" smd circle
			(at 5.199888 6.800088)
			(size 0.3556 0.3556)
			(layers "F.Cu" "F.Mask" "F.Paste")
			(net "GND")
		)
		(pad "AD23" smd circle
			(at 5.999988 6.800088)
			(size 0.3556 0.3556)
			(layers "F.Cu" "F.Mask" "F.Paste")
			(net "GND")
		)
		(pad "AD24" smd circle
			(at 6.800088 6.800088)
			(size 0.3556 0.3556)
			(layers "F.Cu" "F.Mask" "F.Paste")
			(net "GND")
		)
		(pad "AD25" smd circle
			(at 7.599934 6.800088)
			(size 0.3556 0.3556)
			(layers "F.Cu" "F.Mask" "F.Paste")
			(net "GND")
		)
		(pad "AD26" smd circle
			(at 8.400034 6.800088)
			(size 0.3556 0.3556)
			(layers "F.Cu" "F.Mask" "F.Paste")
			(net "P1V8_C")
		)
		(pad "AD27" smd circle
			(at 9.19988 6.800088)
			(size 0.3556 0.3556)
			(layers "F.Cu" "F.Mask" "F.Paste")
			(net "GND")
		)
		(pad "AD28" smd circle
			(at 9.99998 6.800088)
			(size 0.3556 0.3556)
			(layers "F.Cu" "F.Mask" "F.Paste")
			(net "IOC_GPIO_29")
		)
		(pad "AD29" smd circle
			(at 10.80008 6.800088)
			(size 0.3556 0.3556)
			(layers "F.Cu" "F.Mask" "F.Paste")
			(net "IOC_GPIO_27")
		)
		(pad "AD30" smd circle
			(at 11.599926 6.800088)
			(size 0.3556 0.3556)
			(layers "F.Cu" "F.Mask" "F.Paste")
			(net "IOC_GPIO_17")
		)
		(pad "AE1" smd circle
			(at -11.599926 7.599934)
			(size 0.3556 0.3556)
			(layers "F.Cu" "F.Mask" "F.Paste")
			(net "PHY_IOC_TO_SCC_42_DP")
		)
		(pad "AE2" smd circle
			(at -10.80008 7.599934)
			(size 0.3556 0.3556)
			(layers "F.Cu" "F.Mask" "F.Paste")
			(net "PHY_IOC_TO_SCC_42_DN")
		)
		(pad "AE3" smd circle
			(at -9.99998 7.599934)
			(size 0.3556 0.3556)
			(layers "F.Cu" "F.Mask" "F.Paste")
			(net "GND")
		)
		(pad "AE4" smd circle
			(at -9.19988 7.599934)
			(size 0.3556 0.3556)
			(layers "F.Cu" "F.Mask" "F.Paste")
			(net "PHY_SCC_TO_IOC_C_42_DP")
		)
		(pad "AE5" smd circle
			(at -8.400034 7.599934)
			(size 0.3556 0.3556)
			(layers "F.Cu" "F.Mask" "F.Paste")
			(net "PHY_SCC_TO_IOC_C_42_DN")
		)
		(pad "AE6" smd circle
			(at -7.599934 7.599934)
			(size 0.3556 0.3556)
			(layers "F.Cu" "F.Mask" "F.Paste")
			(net "GND")
		)
		(pad "AE7" smd circle
			(at -6.800088 7.599934)
			(size 0.3556 0.3556)
			(layers "F.Cu" "F.Mask" "F.Paste")
			(net "GND")
		)
		(pad "AE8" smd circle
			(at -5.999988 7.599934)
			(size 0.3556 0.3556)
			(layers "F.Cu" "F.Mask" "F.Paste")
			(net "PCE_VDDH")
		)
		(pad "AE9" smd circle
			(at -5.199888 7.599934)
			(size 0.3556 0.3556)
			(layers "F.Cu" "F.Mask" "F.Paste")
			(net "GND")
		)
		(pad "AE10" smd circle
			(at -4.400042 7.599934)
			(size 0.3556 0.3556)
			(layers "F.Cu" "F.Mask" "F.Paste")
			(net "PCE_VDDH")
		)
		(pad "AE11" smd circle
			(at -3.599942 7.599934)
			(size 0.3556 0.3556)
			(layers "F.Cu" "F.Mask" "F.Paste")
			(net "GND")
		)
		(pad "AE12" smd circle
			(at -2.800096 7.599934)
			(size 0.3556 0.3556)
			(layers "F.Cu" "F.Mask" "F.Paste")
			(net "PCE_VDDH")
		)
		(pad "AE13" smd circle
			(at -1.999996 7.599934)
			(size 0.3556 0.3556)
			(layers "F.Cu" "F.Mask" "F.Paste")
			(net "GND")
		)
		(pad "AE14" smd circle
			(at -1.199896 7.599934)
			(size 0.3556 0.3556)
			(layers "F.Cu" "F.Mask" "F.Paste")
			(net "PCE_VDDH")
		)
		(pad "AE15" smd circle
			(at -0.40005 7.599934)
			(size 0.3556 0.3556)
			(layers "F.Cu" "F.Mask" "F.Paste")
			(net "GND")
		)
		(pad "AE16" smd circle
			(at 0.40005 7.599934)
			(size 0.3556 0.3556)
			(layers "F.Cu" "F.Mask" "F.Paste")
			(net "PCE_VDDH")
		)
		(pad "AE17" smd circle
			(at 1.199896 7.599934)
			(size 0.3556 0.3556)
			(layers "F.Cu" "F.Mask" "F.Paste")
			(net "GND")
		)
		(pad "AE18" smd circle
			(at 1.999996 7.599934)
			(size 0.3556 0.3556)
			(layers "F.Cu" "F.Mask" "F.Paste")
			(net "GND")
		)
		(pad "AE19" smd circle
			(at 2.800096 7.599934)
			(size 0.3556 0.3556)
			(layers "F.Cu" "F.Mask" "F.Paste")
			(net "SPARE5")
		)
		(pad "AE20" smd circle
			(at 3.599942 7.599934)
			(size 0.3556 0.3556)
			(layers "F.Cu" "F.Mask" "F.Paste")
			(net "SPARE3")
		)
		(pad "AE21" smd circle
			(at 4.400042 7.599934)
			(size 0.3556 0.3556)
			(layers "F.Cu" "F.Mask" "F.Paste")
			(net "IOC_GPIO_7")
		)
		(pad "AE22" smd circle
			(at 5.199888 7.599934)
			(size 0.3556 0.3556)
			(layers "F.Cu" "F.Mask" "F.Paste")
			(net "SYS_DBMODE0")
		)
		(pad "AE23" smd circle
			(at 5.999988 7.599934)
			(size 0.3556 0.3556)
			(layers "F.Cu" "F.Mask" "F.Paste")
			(net "SYS_RST_N_1")
		)
		(pad "AE24" smd circle
			(at 6.800088 7.599934)
			(size 0.3556 0.3556)
			(layers "F.Cu" "F.Mask" "F.Paste")
			(net "GND")
		)
		(pad "AE25" smd circle
			(at 7.599934 7.599934)
			(size 0.3556 0.3556)
			(layers "F.Cu" "F.Mask" "F.Paste")
			(net "GND")
		)
		(pad "AE26" smd circle
			(at 8.400034 7.599934)
			(size 0.3556 0.3556)
			(layers "F.Cu" "F.Mask" "F.Paste")
			(net "GND")
		)
		(pad "AE27" smd circle
			(at 9.19988 7.599934)
			(size 0.3556 0.3556)
			(layers "F.Cu" "F.Mask" "F.Paste")
			(net "P1V8_C")
		)
		(pad "AE28" smd circle
			(at 9.99998 7.599934)
			(size 0.3556 0.3556)
			(layers "F.Cu" "F.Mask" "F.Paste")
			(net "UART_SERCLK")
		)
		(pad "AE29" smd circle
			(at 10.80008 7.599934)
			(size 0.3556 0.3556)
			(layers "F.Cu" "F.Mask" "F.Paste")
			(net "IOC_GPIO_39")
		)
		(pad "AE30" smd circle
			(at 11.599926 7.599934)
			(size 0.3556 0.3556)
			(layers "F.Cu" "F.Mask" "F.Paste")
			(net "IOC_GPIO_31")
		)
		(pad "AF1" smd circle
			(at -11.599926 8.400034)
			(size 0.3556 0.3556)
			(layers "F.Cu" "F.Mask" "F.Paste")
			(net "SAS0_VDDH")
		)
		(pad "AF2" smd circle
			(at -10.80008 8.400034)
			(size 0.3556 0.3556)
			(layers "F.Cu" "F.Mask" "F.Paste")
			(net "GND")
		)
		(pad "AF3" smd circle
			(at -9.99998 8.400034)
			(size 0.3556 0.3556)
			(layers "F.Cu" "F.Mask" "F.Paste")
			(net "GND")
		)
		(pad "AF4" smd circle
			(at -9.19988 8.400034)
			(size 0.3556 0.3556)
			(layers "F.Cu" "F.Mask" "F.Paste")
			(net "SAS0_AVDD")
		)
		(pad "AF5" smd circle
			(at -8.400034 8.400034)
			(size 0.3556 0.3556)
			(layers "F.Cu" "F.Mask" "F.Paste")
			(net "GND")
		)
		(pad "AF6" smd circle
			(at -7.599934 8.400034)
			(size 0.3556 0.3556)
			(layers "F.Cu" "F.Mask" "F.Paste")
			(net "GND")
		)
		(pad "AF7" smd circle
			(at -6.800088 8.400034)
			(size 0.3556 0.3556)
			(layers "F.Cu" "F.Mask" "F.Paste")
			(net "PCIE_SCC_TO_COMP_C_0_DN")
		)
		(pad "AF8" smd circle
			(at -5.999988 8.400034)
			(size 0.3556 0.3556)
			(layers "F.Cu" "F.Mask" "F.Paste")
			(net "PCIE_SCC_TO_COMP_C_1_DN")
		)
		(pad "AF9" smd circle
			(at -5.199888 8.400034)
			(size 0.3556 0.3556)
			(layers "F.Cu" "F.Mask" "F.Paste")
			(net "GND")
		)
		(pad "AF10" smd circle
			(at -4.400042 8.400034)
			(size 0.3556 0.3556)
			(layers "F.Cu" "F.Mask" "F.Paste")
			(net "PCIE_SCC_TO_COMP_C_2_DN")
		)
		(pad "AF11" smd circle
			(at -3.599942 8.400034)
			(size 0.3556 0.3556)
			(layers "F.Cu" "F.Mask" "F.Paste")
			(net "PCIE_SCC_TO_COMP_C_3_DN")
		)
		(pad "AF12" smd circle
			(at -2.800096 8.400034)
			(size 0.3556 0.3556)
			(layers "F.Cu" "F.Mask" "F.Paste")
			(net "GND")
		)
		(pad "AF13" smd circle
			(at -1.999996 8.400034)
			(size 0.3556 0.3556)
			(layers "F.Cu" "F.Mask" "F.Paste")
			(net "PCIE_SCC_TO_COMP_C_4_DN")
		)
		(pad "AF14" smd circle
			(at -1.199896 8.400034)
			(size 0.3556 0.3556)
			(layers "F.Cu" "F.Mask" "F.Paste")
			(net "PCIE_SCC_TO_COMP_C_5_DN")
		)
		(pad "AF15" smd circle
			(at -0.40005 8.400034)
			(size 0.3556 0.3556)
			(layers "F.Cu" "F.Mask" "F.Paste")
			(net "GND")
		)
		(pad "AF16" smd circle
			(at 0.40005 8.400034)
			(size 0.3556 0.3556)
			(layers "F.Cu" "F.Mask" "F.Paste")
			(net "PCIE_SCC_TO_COMP_C_6_DN")
		)
		(pad "AF17" smd circle
			(at 1.199896 8.400034)
			(size 0.3556 0.3556)
			(layers "F.Cu" "F.Mask" "F.Paste")
			(net "PCIE_SCC_TO_COMP_C_7_DN")
		)
		(pad "AF18" smd circle
			(at 1.999996 8.400034)
			(size 0.3556 0.3556)
			(layers "F.Cu" "F.Mask" "F.Paste")
			(net "GND")
		)
		(pad "AF19" smd circle
			(at 2.800096 8.400034)
			(size 0.3556 0.3556)
			(layers "F.Cu" "F.Mask" "F.Paste")
			(net "GND")
		)
		(pad "AF20" smd circle
			(at 3.599942 8.400034)
			(size 0.3556 0.3556)
			(layers "F.Cu" "F.Mask" "F.Paste")
			(net "P1V8_C")
		)
		(pad "AF21" smd circle
			(at 4.400042 8.400034)
			(size 0.3556 0.3556)
			(layers "F.Cu" "F.Mask" "F.Paste")
			(net "GND")
		)
		(pad "AF22" smd circle
			(at 5.199888 8.400034)
			(size 0.3556 0.3556)
			(layers "F.Cu" "F.Mask" "F.Paste")
			(net "P1V8_C")
		)
		(pad "AF23" smd circle
			(at 5.999988 8.400034)
			(size 0.3556 0.3556)
			(layers "F.Cu" "F.Mask" "F.Paste")
			(net "GND")
		)
		(pad "AF24" smd circle
			(at 6.800088 8.400034)
			(size 0.3556 0.3556)
			(layers "F.Cu" "F.Mask" "F.Paste")
			(net "P1V8_C")
		)
		(pad "AF25" smd circle
			(at 7.599934 8.400034)
			(size 0.3556 0.3556)
			(layers "F.Cu" "F.Mask" "F.Paste")
			(net "GND")
		)
		(pad "AF26" smd circle
			(at 8.400034 8.400034)
			(size 0.3556 0.3556)
			(layers "F.Cu" "F.Mask" "F.Paste")
			(net "P1V8_C")
		)
		(pad "AF27" smd circle
			(at 9.19988 8.400034)
			(size 0.3556 0.3556)
			(layers "F.Cu" "F.Mask" "F.Paste")
			(net "GND")
		)
		(pad "AF28" smd circle
			(at 9.99998 8.400034)
			(size 0.3556 0.3556)
			(layers "F.Cu" "F.Mask" "F.Paste")
			(net "IOC_GPIO_26")
		)
		(pad "AF29" smd circle
			(at 10.80008 8.400034)
			(size 0.3556 0.3556)
			(layers "F.Cu" "F.Mask" "F.Paste")
			(net "IOC_GPIO_0")
		)
		(pad "AF30" smd circle
			(at 11.599926 8.400034)
			(size 0.3556 0.3556)
			(layers "F.Cu" "F.Mask" "F.Paste")
			(net "IOC_GPIO_16")
		)
		(pad "AG1" smd circle
			(at -11.599926 9.19988)
			(size 0.3556 0.3556)
			(layers "F.Cu" "F.Mask" "F.Paste")
			(net "PHY_IOC_TO_SCC_41_DP")
		)
		(pad "AG2" smd circle
			(at -10.80008 9.19988)
			(size 0.3556 0.3556)
			(layers "F.Cu" "F.Mask" "F.Paste")
			(net "PHY_IOC_TO_SCC_41_DN")
		)
		(pad "AG3" smd circle
			(at -9.99998 9.19988)
			(size 0.3556 0.3556)
			(layers "F.Cu" "F.Mask" "F.Paste")
			(net "GND")
		)
		(pad "AG4" smd circle
			(at -9.19988 9.19988)
			(size 0.3556 0.3556)
			(layers "F.Cu" "F.Mask" "F.Paste")
			(net "PHY_SCC_TO_IOC_C_41_DP")
		)
		(pad "AG5" smd circle
			(at -8.400034 9.19988)
			(size 0.3556 0.3556)
			(layers "F.Cu" "F.Mask" "F.Paste")
			(net "PHY_SCC_TO_IOC_C_41_DN")
		)
		(pad "AG6" smd circle
			(at -7.599934 9.19988)
			(size 0.3556 0.3556)
			(layers "F.Cu" "F.Mask" "F.Paste")
			(net "GND")
		)
		(pad "AG7" smd circle
			(at -6.800088 9.19988)
			(size 0.3556 0.3556)
			(layers "F.Cu" "F.Mask" "F.Paste")
			(net "PCIE_SCC_TO_COMP_C_0_DP")
		)
		(pad "AG8" smd circle
			(at -5.999988 9.19988)
			(size 0.3556 0.3556)
			(layers "F.Cu" "F.Mask" "F.Paste")
			(net "PCIE_SCC_TO_COMP_C_1_DP")
		)
		(pad "AG9" smd circle
			(at -5.199888 9.19988)
			(size 0.3556 0.3556)
			(layers "F.Cu" "F.Mask" "F.Paste")
			(net "PCE_VDDH")
		)
		(pad "AG10" smd circle
			(at -4.400042 9.19988)
			(size 0.3556 0.3556)
			(layers "F.Cu" "F.Mask" "F.Paste")
			(net "PCIE_SCC_TO_COMP_C_2_DP")
		)
		(pad "AG11" smd circle
			(at -3.599942 9.19988)
			(size 0.3556 0.3556)
			(layers "F.Cu" "F.Mask" "F.Paste")
			(net "PCIE_SCC_TO_COMP_C_3_DP")
		)
		(pad "AG12" smd circle
			(at -2.800096 9.19988)
			(size 0.3556 0.3556)
			(layers "F.Cu" "F.Mask" "F.Paste")
			(net "PCE_VDDH")
		)
		(pad "AG13" smd circle
			(at -1.999996 9.19988)
			(size 0.3556 0.3556)
			(layers "F.Cu" "F.Mask" "F.Paste")
			(net "PCIE_SCC_TO_COMP_C_4_DP")
		)
		(pad "AG14" smd circle
			(at -1.199896 9.19988)
			(size 0.3556 0.3556)
			(layers "F.Cu" "F.Mask" "F.Paste")
			(net "PCIE_SCC_TO_COMP_C_5_DP")
		)
		(pad "AG15" smd circle
			(at -0.40005 9.19988)
			(size 0.3556 0.3556)
			(layers "F.Cu" "F.Mask" "F.Paste")
			(net "GND")
		)
		(pad "AG16" smd circle
			(at 0.40005 9.19988)
			(size 0.3556 0.3556)
			(layers "F.Cu" "F.Mask" "F.Paste")
			(net "PCIE_SCC_TO_COMP_C_6_DP")
		)
		(pad "AG17" smd circle
			(at 1.199896 9.19988)
			(size 0.3556 0.3556)
			(layers "F.Cu" "F.Mask" "F.Paste")
			(net "PCIE_SCC_TO_COMP_C_7_DP")
		)
		(pad "AG18" smd circle
			(at 1.999996 9.19988)
			(size 0.3556 0.3556)
			(layers "F.Cu" "F.Mask" "F.Paste")
			(net "PCE_VDDH")
		)
		(pad "AG19" smd circle
			(at 2.800096 9.19988)
			(size 0.3556 0.3556)
			(layers "F.Cu" "F.Mask" "F.Paste")
			(net "P1V8_C")
		)
		(pad "AG20" smd circle
			(at 3.599942 9.19988)
			(size 0.3556 0.3556)
			(layers "F.Cu" "F.Mask" "F.Paste")
			(net "GND")
		)
		(pad "AG21" smd circle
			(at 4.400042 9.19988)
			(size 0.3556 0.3556)
			(layers "F.Cu" "F.Mask" "F.Paste")
			(net "P1V8_C")
		)
		(pad "AG22" smd circle
			(at 5.199888 9.19988)
			(size 0.3556 0.3556)
			(layers "F.Cu" "F.Mask" "F.Paste")
			(net "GND")
		)
		(pad "AG23" smd circle
			(at 5.999988 9.19988)
			(size 0.3556 0.3556)
			(layers "F.Cu" "F.Mask" "F.Paste")
			(net "P1V8_C")
		)
		(pad "AG24" smd circle
			(at 6.800088 9.19988)
			(size 0.3556 0.3556)
			(layers "F.Cu" "F.Mask" "F.Paste")
			(net "GND")
		)
		(pad "AG25" smd circle
			(at 7.599934 9.19988)
			(size 0.3556 0.3556)
			(layers "F.Cu" "F.Mask" "F.Paste")
			(net "P1V8_C")
		)
		(pad "AG26" smd circle
			(at 8.400034 9.19988)
			(size 0.3556 0.3556)
			(layers "F.Cu" "F.Mask" "F.Paste")
			(net "GND")
		)
		(pad "AG27" smd circle
			(at 9.19988 9.19988)
			(size 0.3556 0.3556)
			(layers "F.Cu" "F.Mask" "F.Paste")
			(net "P1V8_C")
		)
		(pad "AG28" smd circle
			(at 9.99998 9.19988)
			(size 0.3556 0.3556)
			(layers "F.Cu" "F.Mask" "F.Paste")
			(net "IOC_GPIO_25")
		)
		(pad "AG29" smd circle
			(at 10.80008 9.19988)
			(size 0.3556 0.3556)
			(layers "F.Cu" "F.Mask" "F.Paste")
			(net "IOC_GPIO_18")
		)
		(pad "AG30" smd circle
			(at 11.599926 9.19988)
			(size 0.3556 0.3556)
			(layers "F.Cu" "F.Mask" "F.Paste")
			(net "IOC_GPIO_21")
		)
	)
)
